# BASEBOARD_FAB2 (Tioga Pass) — schematic netlist excerpt (pin names and nets, part order shuffled) for the footprints in the layout excerpt that follows; sources: Cadence DE-HDL packaged netlist, KiCad conversion of Wiwynn_Tioga_Pass_MB.brd

C25W96  CAP_A  0.1UF 16V 10% X7R  pkg 0402V  page 255 : A = P3V3_STBY ; B = GND
C4T3  CAPP  220UF 4V 20% POSCAP  pkg 7343  page 231 : A = PVPP_ABC ; B = GND
R1R18  RES  2.21K 1% CHIP  pkg 0402  page 188 : A = P3V3_STBY ; B = SMB_PCH_MEZZ_LOM0_SCL

(kicad_pcb
	(version 20260206)
	(generator "pcbnew")
	(generator_version "10.0")
	(general
		(thickness 1.6)
		(legacy_teardrops no)
	)
	(paper "A4")
	(title_block
		(title "Wiwynn_Tioga_Pass_MB.brd")
		(comment 1 "Tioga Pass / footprints 3177-3179 of 4770")
	)
	(layers
		(0 "F.Cu" signal "TOP")
		(4 "In1.Cu" signal "L2GND")
		(6 "In2.Cu" signal "L3")
		(8 "In3.Cu" signal "L4GND")
		(10 "In4.Cu" signal "L5")
		(12 "In5.Cu" signal "L6GND")
		(14 "In6.Cu" signal "L7VCC")
		(16 "In7.Cu" signal "L8VCC")
		(18 "In8.Cu" signal "L9GND")
		(20 "In9.Cu" signal "L10")
		(22 "In10.Cu" signal "L11GND")
		(24 "In11.Cu" signal "L12")
		(26 "In12.Cu" signal "L13GND")
		(2 "B.Cu" signal "BOTTOM")
		(9 "F.Adhes" user "F.Adhesive")
		(11 "B.Adhes" user "B.Adhesive")
		(13 "F.Paste" user "Package Geometry/Pastemask Top")
		(15 "B.Paste" user "Package Geometry/Pastemask Bottom")
		(5 "F.SilkS" user "Ref Des/Silkscreen Top")
		(7 "B.SilkS" user "Ref Des/Silkscreen Bottom")
		(1 "F.Mask" user "Board Geometry/Soldermask Top")
		(3 "B.Mask" user "Board Geometry/Soldermask Bottom")
		(17 "Dwgs.User" user "User.Drawings")
		(19 "Cmts.User" user "User.Comments")
		(21 "Eco1.User" user "User.Eco1")
		(23 "Eco2.User" user "User.Eco2")
		(25 "Edge.Cuts" user "Board Geometry/Outline")
		(27 "Margin" user)
		(31 "F.CrtYd" user "Package Geometry/Place Bound Top")
		(29 "B.CrtYd" user "Package Geometry/Place Bound Bottom")
		(35 "F.Fab" user "Ref Des/Assembly Top")
		(33 "B.Fab" user "Ref Des/Assembly Bottom")
	)
	(footprint ""
		(layer "B.Cu")
		(at 447.079878 -152.842722)
		(property "Reference" "C25W96"
			(at 0.8382 -0.67818 0)
			(unlocked yes)
			(layer "B.SilkS")
			(effects
				(font
					(size 0.4064 0.254)
					(thickness 0.1524)
				)
				(justify left mirror)
			)
		)
		(property "Value" ""
			(at 0 0 0)
			(layer "B.Fab")
			(effects
				(font
					(size 1.27 1.27)
				)
				(justify mirror)
			)
		)
		(duplicate_pad_numbers_are_jumpers no)
		(fp_poly
			(pts
				(xy -0.3048 -0.1016) (xy -0.3048 0.9906) (xy 0.3048 0.9906) (xy 0.3048 -0.1016)
			)
			(stroke
				(width 0)
				(type default)
			)
			(fill no)
			(layer "B.CrtYd")
		)
		(fp_line
			(start -0.3048 -0.1016)
			(end 0.3048 -0.1016)
			(stroke
				(width 0.1)
				(type default)
			)
			(layer "B.Fab")
		)
		(fp_line
			(start -0.3048 0.9906)
			(end -0.3048 -0.1016)
			(stroke
				(width 0.1)
				(type default)
			)
			(layer "B.Fab")
		)
		(fp_line
			(start 0.3048 -0.1016)
			(end 0.3048 0.9906)
			(stroke
				(width 0.1)
				(type default)
			)
			(layer "B.Fab")
		)
		(fp_line
			(start 0.3048 0.9906)
			(end -0.3048 0.9906)
			(stroke
				(width 0.1)
				(type default)
			)
			(layer "B.Fab")
		)
		(pad "1" smd rect
			(at 0 0 180)
			(size 0.508 0.508)
			(layers "B.Cu" "B.Mask" "B.Paste")
			(net "P3V3_STBY")
		)
		(pad "2" smd rect
			(at 0 0.889 180)
			(size 0.508 0.508)
			(layers "B.Cu" "B.Mask" "B.Paste")
			(net "GND")
		)
		(zone
			(layer "B.Cu")
			(hatch none 0.5)
			(connect_pads
				(clearance 0)
			)
			(min_thickness 0.25)
			(keepout
				(tracks allowed)
				(vias not_allowed)
				(pads allowed)
				(copperpour not_allowed)
				(footprints allowed)
			)
			(placement
				(enabled no)
				(sheetname "")
			)
			(fill
				(thermal_gap 0.5)
				(thermal_bridge_width 0.5)
				(island_removal_mode 0)
			)
			(polygon
				(pts
					(xy 447.333878 -152.588722) (xy 446.825878 -152.588722) (xy 446.825878 -152.207722) (xy 447.333878 -152.207722)
				)
			)
		)
		(zone
			(layer "B.Cu")
			(hatch none 0.5)
			(connect_pads
				(clearance 0)
			)
			(min_thickness 0.25)
			(keepout
				(tracks not_allowed)
				(vias allowed)
				(pads allowed)
				(copperpour not_allowed)
				(footprints allowed)
			)
			(placement
				(enabled no)
				(sheetname "")
			)
			(fill
				(thermal_gap 0.5)
				(thermal_bridge_width 0.5)
				(island_removal_mode 0)
			)
			(polygon
				(pts
					(xy 447.333878 -152.207722) (xy 446.825878 -152.207722) (xy 446.825878 -152.588722) (xy 447.333878 -152.588722)
				)
			)
		)
	)
	(footprint ""
		(layer "B.Cu")
		(at 470.027 -60.96 -90)
		(property "Reference" "R1R18"
			(at 0 0 90)
			(layer "B.SilkS")
			(hide yes)
			(effects
				(font
					(size 1.27 1.27)
				)
				(justify mirror)
			)
		)
		(property "Value" ""
			(at 0 0 90)
			(layer "B.Fab")
			(effects
				(font
					(size 1.27 1.27)
				)
				(justify mirror)
			)
		)
		(duplicate_pad_numbers_are_jumpers no)
		(fp_poly
			(pts
				(xy 0.2794 -0.1016) (xy -0.2794 -0.1016) (xy -0.2794 0.9906) (xy 0.2794 0.9906)
			)
			(stroke
				(width 0)
				(type default)
			)
			(fill no)
			(layer "B.CrtYd")
		)
		(fp_line
			(start -0.2794 0.9906)
			(end -0.2794 -0.1016)
			(stroke
				(width 0.1)
				(type default)
			)
			(layer "B.Fab")
		)
		(fp_line
			(start 0.2794 0.9906)
			(end -0.2794 0.9906)
			(stroke
				(width 0.1)
				(type default)
			)
			(layer "B.Fab")
		)
		(fp_line
			(start -0.2794 -0.1016)
			(end 0.2794 -0.1016)
			(stroke
				(width 0.1)
				(type default)
			)
			(layer "B.Fab")
		)
		(fp_line
			(start 0.2794 -0.1016)
			(end 0.2794 0.9906)
			(stroke
				(width 0.1)
				(type default)
			)
			(layer "B.Fab")
		)
		(pad "1" smd rect
			(at 0 0 90)
			(size 0.508 0.508)
			(layers "B.Cu" "B.Mask" "B.Paste")
			(net "P3V3_STBY")
		)
		(pad "2" smd rect
			(at 0 0.889 90)
			(size 0.508 0.508)
			(layers "B.Cu" "B.Mask" "B.Paste")
			(net "SMB_PCH_MEZZ_LOM0_SCL")
		)
		(zone
			(layer "B.Cu")
			(hatch none 0.5)
			(connect_pads
				(clearance 0)
			)
			(min_thickness 0.25)
			(keepout
				(tracks not_allowed)
				(vias allowed)
				(pads allowed)
				(copperpour not_allowed)
				(footprints allowed)
			)
			(placement
				(enabled no)
				(sheetname "")
			)
			(fill
				(thermal_gap 0.5)
				(thermal_bridge_width 0.5)
				(island_removal_mode 0)
			)
			(polygon
				(pts
					(xy 469.392 -60.706) (xy 469.392 -61.214) (xy 469.773 -61.214) (xy 469.773 -60.706)
				)
			)
		)
		(zone
			(layer "B.Cu")
			(hatch none 0.5)
			(connect_pads
				(clearance 0)
			)
			(min_thickness 0.25)
			(keepout
				(tracks allowed)
				(vias not_allowed)
				(pads allowed)
				(copperpour not_allowed)
				(footprints allowed)
			)
			(placement
				(enabled no)
				(sheetname "")
			)
			(fill
				(thermal_gap 0.5)
				(thermal_bridge_width 0.5)
				(island_removal_mode 0)
			)
			(polygon
				(pts
					(xy 469.773 -60.706) (xy 469.773 -61.214) (xy 469.392 -61.214) (xy 469.392 -60.706)
				)
			)
		)
	)
	(footprint ""
		(layer "B.Cu")
		(at 329.2094 -27.6733 180)
		(property "Reference" "C4T3"
			(at -3.12293 2.9083 270)
			(unlocked yes)
			(layer "B.SilkS")
			(effects
				(font
					(size 0.7874 0.5842)
					(thickness 0.1524)
				)
				(justify left mirror)
			)
		)
		(property "Value" ""
			(at 0 0 0)
			(layer "B.Fab")
			(effects
				(font
					(size 1.27 1.27)
				)
				(justify mirror)
			)
		)
		(duplicate_pad_numbers_are_jumpers no)
		(fp_line
			(start 2.2987 7.3533)
			(end 1.7272 7.3533)
			(stroke
				(width 0.1524)
				(type default)
			)
			(layer "B.SilkS")
		)
		(fp_line
			(start 2.2987 -0.2413)
			(end 2.2987 7.3533)
			(stroke
				(width 0.1524)
				(type default)
			)
			(layer "B.SilkS")
		)
		(fp_line
			(start 2.032 1.524)
			(end 1.7272 1.524)
			(stroke
				(width 0.1524)
				(type default)
			)
			(layer "B.SilkS")
		)
		(fp_line
			(start 2.032 -0.2413)
			(end 2.2987 -0.2413)
			(stroke
				(width 0.1524)
				(type default)
			)
			(layer "B.SilkS")
		)
		(fp_line
			(start 2.032 -1.524)
			(end 2.032 1.524)
			(stroke
				(width 0.1524)
				(type default)
			)
			(layer "B.SilkS")
		)
		(fp_line
			(start 1.7272 -1.524)
			(end 2.032 -1.524)
			(stroke
				(width 0.1524)
				(type default)
			)
			(layer "B.SilkS")
		)
		(fp_line
			(start -1.7272 7.3533)
			(end -2.2987 7.3533)
			(stroke
				(width 0.1524)
				(type default)
			)
			(layer "B.SilkS")
		)
		(fp_line
			(start -1.7272 -1.524)
			(end -2.032 -1.524)
			(stroke
				(width 0.1524)
				(type default)
			)
			(layer "B.SilkS")
		)
		(fp_line
			(start -2.032 1.524)
			(end -1.7272 1.524)
			(stroke
				(width 0.1524)
				(type default)
			)
			(layer "B.SilkS")
		)
		(fp_line
			(start -2.032 -1.524)
			(end -2.032 1.524)
			(stroke
				(width 0.1524)
				(type default)
			)
			(layer "B.SilkS")
		)
		(fp_line
			(start -2.2987 7.3533)
			(end -2.2987 -0.2413)
			(stroke
				(width 0.1524)
				(type default)
			)
			(layer "B.SilkS")
		)
		(fp_line
			(start -2.2987 -0.2413)
			(end -2.032 -0.2413)
			(stroke
				(width 0.1524)
				(type default)
			)
			(layer "B.SilkS")
		)
		(fp_rect
			(start 2.2987 -0.2413)
			(end -2.2987 7.3533)
			(stroke
				(width 0)
				(type default)
			)
			(fill no)
			(layer "B.CrtYd")
		)
		(fp_line
			(start 2.2987 7.3533)
			(end 2.2987 -0.2413)
			(stroke
				(width 0.1)
				(type default)
			)
			(layer "B.Fab")
		)
		(fp_line
			(start 2.2987 -0.2413)
			(end -2.2987 -0.2413)
			(stroke
				(width 0.1)
				(type default)
			)
			(layer "B.Fab")
		)
		(fp_line
			(start -2.2987 7.3533)
			(end 2.2987 7.3533)
			(stroke
				(width 0.1)
				(type default)
			)
			(layer "B.Fab")
		)
		(fp_line
			(start -2.2987 -0.2413)
			(end -2.2987 7.3533)
			(stroke
				(width 0.1)
				(type default)
			)
			(layer "B.Fab")
		)
		(pad "1" smd rect
			(at 0 0)
			(size 2.54 3.048)
			(layers "B.Cu" "B.Mask" "B.Paste")
			(net "PVPP_ABC")
		)
		(pad "2" smd rect
			(at 0 7.112)
			(size 2.54 3.048)
			(layers "B.Cu" "B.Mask" "B.Paste")
			(net "GND")
		)
	)
)
